(kicad_pcb
	(version 20260206)
	(generator "pcbnew")
	(generator_version "10.0")
	(general
		(thickness 1.6)
		(legacy_teardrops no)
	)
	(paper "A4")
	(title_block
		(title "v1-pdb — T6M_PDB_D_0927_0900.brd")
		(comment 1 "Open CloudServer (Microsoft) / footprints 162-171 of 321")
	)
	(layers
		(0 "F.Cu" signal "TOP")
		(4 "In1.Cu" signal "GND")
		(6 "In2.Cu" signal "IN1")
		(8 "In3.Cu" signal "VCC")
		(10 "In4.Cu" signal "VCC1")
		(12 "In5.Cu" signal "IN2")
		(14 "In6.Cu" signal "GND1")
		(2 "B.Cu" signal "BOTTOM")
		(9 "F.Adhes" user "F.Adhesive")
		(11 "B.Adhes" user "B.Adhesive")
		(13 "F.Paste" user "Package Geometry/Pastemask Top")
		(15 "B.Paste" user "Package Geometry/Pastemask Bottom")
		(5 "F.SilkS" user "Ref Des/Silkscreen Top")
		(7 "B.SilkS" user "Ref Des/Silkscreen Bottom")
		(1 "F.Mask" user "Board Geometry/Soldermask Top")
		(3 "B.Mask" user "Board Geometry/Soldermask Bottom")
		(17 "Dwgs.User" user "User.Drawings")
		(19 "Cmts.User" user "User.Comments")
		(21 "Eco1.User" user "User.Eco1")
		(23 "Eco2.User" user "User.Eco2")
		(25 "Edge.Cuts" user "Board Geometry/Outline")
		(27 "Margin" user)
		(31 "F.CrtYd" user "Package Geometry/Place Bound Top")
		(29 "B.CrtYd" user "Package Geometry/Place Bound Bottom")
		(35 "F.Fab" user "Ref Des/Assembly Top")
		(33 "B.Fab" user "Ref Des/Assembly Bottom")
	)
	(footprint ""
		(layer "F.Cu")
		(at 13.420852 -318.358012 180)
		(property "Reference" "R140"
			(at -1.72974 -0.146304 0)
			(unlocked yes)
			(layer "F.SilkS")
			(effects
				(font
					(size 0.7874 0.5842)
					(thickness 0.1524)
				)
				(justify left)
			)
		)
		(property "Value" ""
			(at 0 0 180)
			(layer "F.Fab")
			(effects
				(font
					(size 1.27 1.27)
				)
			)
		)
		(duplicate_pad_numbers_are_jumpers no)
		(fp_line
			(start 0.7874 0.4064)
			(end -0.7874 0.4064)
			(stroke
				(width 0.1524)
				(type default)
			)
			(layer "F.SilkS")
		)
		(fp_line
			(start 0.7874 -0.4064)
			(end 0.7874 0.4064)
			(stroke
				(width 0.1524)
				(type default)
			)
			(layer "F.SilkS")
		)
		(fp_line
			(start -0.7874 0.4064)
			(end -0.7874 -0.4064)
			(stroke
				(width 0.1524)
				(type default)
			)
			(layer "F.SilkS")
		)
		(fp_line
			(start -0.7874 -0.4064)
			(end 0.7874 -0.4064)
			(stroke
				(width 0.1524)
				(type default)
			)
			(layer "F.SilkS")
		)
		(fp_poly
			(pts
				(xy -0.508 0.2794) (xy -0.508 0.2286) (xy -0.635 0.2286) (xy -0.635 -0.254) (xy -0.5334 -0.254)
				(xy -0.5334 -0.2794) (xy 0.5334 -0.2794) (xy 0.5334 -0.254) (xy 0.635 -0.254) (xy 0.635 0.254) (xy 0.5334 0.254)
				(xy 0.5334 0.2794)
			)
			(stroke
				(width 0)
				(type default)
			)
			(fill no)
			(layer "F.CrtYd")
		)
		(pad "1" smd rect
			(at 0.40005 0 180)
			(size 0.4572 0.508)
			(layers "F.Cu" "F.Mask" "F.Paste")
			(net "FAN_PWM")
		)
		(pad "2" smd rect
			(at -0.40005 0 180)
			(size 0.4572 0.508)
			(layers "F.Cu" "F.Mask" "F.Paste")
			(net "GND")
		)
	)
	(footprint ""
		(layer "F.Cu")
		(at 73.426828 -307.819806 90)
		(property "Reference" "C54"
			(at -1.283716 5.297424 90)
			(unlocked yes)
			(layer "F.SilkS")
			(effects
				(font
					(size 0.7874 0.5842)
					(thickness 0.1524)
				)
				(justify left)
			)
		)
		(property "Value" ""
			(at 0 0 90)
			(layer "F.Fab")
			(effects
				(font
					(size 1.27 1.27)
				)
			)
		)
		(duplicate_pad_numbers_are_jumpers no)
		(fp_line
			(start 0.7874 -0.4064)
			(end 0.7874 0.4064)
			(stroke
				(width 0.1524)
				(type default)
			)
			(layer "F.SilkS")
		)
		(fp_line
			(start -0.7874 -0.4064)
			(end 0.7874 -0.4064)
			(stroke
				(width 0.1524)
				(type default)
			)
			(layer "F.SilkS")
		)
		(fp_line
			(start 0 0.381)
			(end 0 -0.381)
			(stroke
				(width 0.1524)
				(type default)
			)
			(layer "F.SilkS")
		)
		(fp_line
			(start 0.7874 0.4064)
			(end -0.7874 0.4064)
			(stroke
				(width 0.1524)
				(type default)
			)
			(layer "F.SilkS")
		)
		(fp_line
			(start -0.7874 0.4064)
			(end -0.7874 -0.4064)
			(stroke
				(width 0.1524)
				(type default)
			)
			(layer "F.SilkS")
		)
		(fp_poly
			(pts
				(xy -0.5334 0.254) (xy -0.635 0.254) (xy -0.635 0.2286) (xy -0.635 -0.254) (xy -0.5334 -0.254) (xy -0.5334 -0.2794)
				(xy 0.5334 -0.2794) (xy 0.5334 -0.254) (xy 0.635 -0.254) (xy 0.635 0.254) (xy 0.5334 0.254) (xy 0.5334 0.2794)
				(xy -0.508 0.2794) (xy -0.5334 0.2794)
			)
			(stroke
				(width 0)
				(type default)
			)
			(fill no)
			(layer "F.CrtYd")
		)
		(pad "1" smd rect
			(at 0.40005 0 90)
			(size 0.4572 0.508)
			(layers "F.Cu" "F.Mask" "F.Paste")
			(net "P12V")
		)
		(pad "2" smd rect
			(at -0.40005 0 90)
			(size 0.4572 0.508)
			(layers "F.Cu" "F.Mask" "F.Paste")
			(net "GND")
		)
	)
	(footprint ""
		(layer "F.Cu")
		(at 77.254354 -14.939772 -90)
		(property "Reference" "C3"
			(at -1.75133 0.09906 90)
			(unlocked yes)
			(layer "F.SilkS")
			(effects
				(font
					(size 0.7874 0.5842)
					(thickness 0.1524)
				)
				(justify left)
			)
		)
		(property "Value" ""
			(at 0 0 270)
			(layer "F.Fab")
			(effects
				(font
					(size 1.27 1.27)
				)
			)
		)
		(duplicate_pad_numbers_are_jumpers no)
		(fp_line
			(start -0.7874 0.4064)
			(end -0.7874 -0.4064)
			(stroke
				(width 0.1524)
				(type default)
			)
			(layer "F.SilkS")
		)
		(fp_line
			(start 0.7874 0.4064)
			(end -0.7874 0.4064)
			(stroke
				(width 0.1524)
				(type default)
			)
			(layer "F.SilkS")
		)
		(fp_line
			(start 0 0.381)
			(end 0 -0.381)
			(stroke
				(width 0.1524)
				(type default)
			)
			(layer "F.SilkS")
		)
		(fp_line
			(start -0.7874 -0.4064)
			(end 0.7874 -0.4064)
			(stroke
				(width 0.1524)
				(type default)
			)
			(layer "F.SilkS")
		)
		(fp_line
			(start 0.7874 -0.4064)
			(end 0.7874 0.4064)
			(stroke
				(width 0.1524)
				(type default)
			)
			(layer "F.SilkS")
		)
		(fp_poly
			(pts
				(xy -0.5334 0.254) (xy -0.635 0.254) (xy -0.635 0.2286) (xy -0.635 -0.254) (xy -0.5334 -0.254) (xy -0.5334 -0.2794)
				(xy 0.5334 -0.2794) (xy 0.5334 -0.254) (xy 0.635 -0.254) (xy 0.635 0.254) (xy 0.5334 0.254) (xy 0.5334 0.2794)
				(xy -0.508 0.2794) (xy -0.5334 0.2794)
			)
			(stroke
				(width 0)
				(type default)
			)
			(fill no)
			(layer "F.CrtYd")
		)
		(pad "1" smd rect
			(at 0.40005 0 270)
			(size 0.4572 0.508)
			(layers "F.Cu" "F.Mask" "F.Paste")
			(net "P12V")
		)
		(pad "2" smd rect
			(at -0.40005 0 270)
			(size 0.4572 0.508)
			(layers "F.Cu" "F.Mask" "F.Paste")
			(net "GND")
		)
	)
	(footprint ""
		(layer "F.Cu")
		(at 17.162272 -330.455524 -90)
		(property "Reference" "R39"
			(at 3.685032 -0.234188 90)
			(unlocked yes)
			(layer "F.SilkS")
			(effects
				(font
					(size 0.7874 0.5842)
					(thickness 0.1524)
				)
				(justify left)
			)
		)
		(property "Value" ""
			(at 0 0 270)
			(layer "F.Fab")
			(effects
				(font
					(size 1.27 1.27)
				)
			)
		)
		(duplicate_pad_numbers_are_jumpers no)
		(fp_line
			(start -0.7874 0.4064)
			(end -0.7874 -0.4064)
			(stroke
				(width 0.1524)
				(type default)
			)
			(layer "F.SilkS")
		)
		(fp_line
			(start 0.7874 0.4064)
			(end -0.7874 0.4064)
			(stroke
				(width 0.1524)
				(type default)
			)
			(layer "F.SilkS")
		)
		(fp_line
			(start -0.7874 -0.4064)
			(end 0.7874 -0.4064)
			(stroke
				(width 0.1524)
				(type default)
			)
			(layer "F.SilkS")
		)
		(fp_line
			(start 0.7874 -0.4064)
			(end 0.7874 0.4064)
			(stroke
				(width 0.1524)
				(type default)
			)
			(layer "F.SilkS")
		)
		(fp_poly
			(pts
				(xy -0.508 0.2794) (xy -0.508 0.2286) (xy -0.635 0.2286) (xy -0.635 -0.254) (xy -0.5334 -0.254)
				(xy -0.5334 -0.2794) (xy 0.5334 -0.2794) (xy 0.5334 -0.254) (xy 0.635 -0.254) (xy 0.635 0.254) (xy 0.5334 0.254)
				(xy 0.5334 0.2794)
			)
			(stroke
				(width 0)
				(type default)
			)
			(fill no)
			(layer "F.CrtYd")
		)
		(pad "1" smd rect
			(at 0.40005 0 270)
			(size 0.4572 0.508)
			(layers "F.Cu" "F.Mask" "F.Paste")
			(net "GND")
		)
		(pad "2" smd rect
			(at -0.40005 0 270)
			(size 0.4572 0.508)
			(layers "F.Cu" "F.Mask" "F.Paste")
			(net "FRU_A2")
		)
	)
	(footprint ""
		(layer "F.Cu")
		(at 78.062074 -387.197854 180)
		(property "Reference" "R127"
			(at 0.888492 1.176274 0)
			(unlocked yes)
			(layer "F.SilkS")
			(effects
				(font
					(size 0.7874 0.5842)
					(thickness 0.1524)
				)
				(justify left)
			)
		)
		(property "Value" ""
			(at 0 0 180)
			(layer "F.Fab")
			(effects
				(font
					(size 1.27 1.27)
				)
			)
		)
		(duplicate_pad_numbers_are_jumpers no)
		(fp_line
			(start 0.7874 0.4064)
			(end -0.7874 0.4064)
			(stroke
				(width 0.1524)
				(type default)
			)
			(layer "F.SilkS")
		)
		(fp_line
			(start 0.7874 -0.4064)
			(end 0.7874 0.4064)
			(stroke
				(width 0.1524)
				(type default)
			)
			(layer "F.SilkS")
		)
		(fp_line
			(start -0.7874 0.4064)
			(end -0.7874 -0.4064)
			(stroke
				(width 0.1524)
				(type default)
			)
			(layer "F.SilkS")
		)
		(fp_line
			(start -0.7874 -0.4064)
			(end 0.7874 -0.4064)
			(stroke
				(width 0.1524)
				(type default)
			)
			(layer "F.SilkS")
		)
		(fp_poly
			(pts
				(xy -0.508 0.2794) (xy -0.508 0.2286) (xy -0.635 0.2286) (xy -0.635 -0.254) (xy -0.5334 -0.254)
				(xy -0.5334 -0.2794) (xy 0.5334 -0.2794) (xy 0.5334 -0.254) (xy 0.635 -0.254) (xy 0.635 0.254) (xy 0.5334 0.254)
				(xy 0.5334 0.2794)
			)
			(stroke
				(width 0)
				(type default)
			)
			(fill no)
			(layer "F.CrtYd")
		)
		(pad "1" smd rect
			(at 0.40005 0 180)
			(size 0.4572 0.508)
			(layers "F.Cu" "F.Mask" "F.Paste")
			(net "PSU5_REMOTE_R2_P")
		)
		(pad "2" smd rect
			(at -0.40005 0 180)
			(size 0.4572 0.508)
			(layers "F.Cu" "F.Mask" "F.Paste")
			(net "P12V")
		)
	)
	(footprint ""
		(layer "F.Cu")
		(at 71.007986 -307.819806 90)
		(property "Reference" "C56"
			(at -1.229106 5.06476 90)
			(unlocked yes)
			(layer "F.SilkS")
			(effects
				(font
					(size 0.7874 0.5842)
					(thickness 0.1524)
				)
				(justify left)
			)
		)
		(property "Value" ""
			(at 0 0 90)
			(layer "F.Fab")
			(effects
				(font
					(size 1.27 1.27)
				)
			)
		)
		(duplicate_pad_numbers_are_jumpers no)
		(fp_line
			(start 0.7874 -0.4064)
			(end 0.7874 0.4064)
			(stroke
				(width 0.1524)
				(type default)
			)
			(layer "F.SilkS")
		)
		(fp_line
			(start -0.7874 -0.4064)
			(end 0.7874 -0.4064)
			(stroke
				(width 0.1524)
				(type default)
			)
			(layer "F.SilkS")
		)
		(fp_line
			(start 0 0.381)
			(end 0 -0.381)
			(stroke
				(width 0.1524)
				(type default)
			)
			(layer "F.SilkS")
		)
		(fp_line
			(start 0.7874 0.4064)
			(end -0.7874 0.4064)
			(stroke
				(width 0.1524)
				(type default)
			)
			(layer "F.SilkS")
		)
		(fp_line
			(start -0.7874 0.4064)
			(end -0.7874 -0.4064)
			(stroke
				(width 0.1524)
				(type default)
			)
			(layer "F.SilkS")
		)
		(fp_poly
			(pts
				(xy -0.5334 0.254) (xy -0.635 0.254) (xy -0.635 0.2286) (xy -0.635 -0.254) (xy -0.5334 -0.254) (xy -0.5334 -0.2794)
				(xy 0.5334 -0.2794) (xy 0.5334 -0.254) (xy 0.635 -0.254) (xy 0.635 0.254) (xy 0.5334 0.254) (xy 0.5334 0.2794)
				(xy -0.508 0.2794) (xy -0.5334 0.2794)
			)
			(stroke
				(width 0)
				(type default)
			)
			(fill no)
			(layer "F.CrtYd")
		)
		(pad "1" smd rect
			(at 0.40005 0 90)
			(size 0.4572 0.508)
			(layers "F.Cu" "F.Mask" "F.Paste")
			(net "P12V")
		)
		(pad "2" smd rect
			(at -0.40005 0 90)
			(size 0.4572 0.508)
			(layers "F.Cu" "F.Mask" "F.Paste")
			(net "GND")
		)
	)
	(footprint ""
		(layer "F.Cu")
		(at 70.678548 -487.29138 90)
		(property "Reference" "C83"
			(at -4.10845 0.070104 90)
			(unlocked yes)
			(layer "F.SilkS")
			(effects
				(font
					(size 0.7874 0.5842)
					(thickness 0.1524)
				)
				(justify left)
			)
		)
		(property "Value" ""
			(at 0 0 90)
			(layer "F.Fab")
			(effects
				(font
					(size 1.27 1.27)
				)
			)
		)
		(duplicate_pad_numbers_are_jumpers no)
		(fp_line
			(start 0.7874 -0.4064)
			(end 0.7874 0.4064)
			(stroke
				(width 0.1524)
				(type default)
			)
			(layer "F.SilkS")
		)
		(fp_line
			(start -0.7874 -0.4064)
			(end 0.7874 -0.4064)
			(stroke
				(width 0.1524)
				(type default)
			)
			(layer "F.SilkS")
		)
		(fp_line
			(start 0 0.381)
			(end 0 -0.381)
			(stroke
				(width 0.1524)
				(type default)
			)
			(layer "F.SilkS")
		)
		(fp_line
			(start 0.7874 0.4064)
			(end -0.7874 0.4064)
			(stroke
				(width 0.1524)
				(type default)
			)
			(layer "F.SilkS")
		)
		(fp_line
			(start -0.7874 0.4064)
			(end -0.7874 -0.4064)
			(stroke
				(width 0.1524)
				(type default)
			)
			(layer "F.SilkS")
		)
		(fp_poly
			(pts
				(xy -0.5334 0.254) (xy -0.635 0.254) (xy -0.635 0.2286) (xy -0.635 -0.254) (xy -0.5334 -0.254) (xy -0.5334 -0.2794)
				(xy 0.5334 -0.2794) (xy 0.5334 -0.254) (xy 0.635 -0.254) (xy 0.635 0.254) (xy 0.5334 0.254) (xy 0.5334 0.2794)
				(xy -0.508 0.2794) (xy -0.5334 0.2794)
			)
			(stroke
				(width 0)
				(type default)
			)
			(fill no)
			(layer "F.CrtYd")
		)
		(pad "1" smd rect
			(at 0.40005 0 90)
			(size 0.4572 0.508)
			(layers "F.Cu" "F.Mask" "F.Paste")
			(net "P12V")
		)
		(pad "2" smd rect
			(at -0.40005 0 90)
			(size 0.4572 0.508)
			(layers "F.Cu" "F.Mask" "F.Paste")
			(net "GND")
		)
	)
	(footprint ""
		(layer "F.Cu")
		(at 70.997572 -354.308664 90)
		(property "Reference" "C61"
			(at -3.90779 0.6096 90)
			(unlocked yes)
			(layer "F.SilkS")
			(effects
				(font
					(size 0.7874 0.5842)
					(thickness 0.1524)
				)
				(justify left)
			)
		)
		(property "Value" ""
			(at 0 0 90)
			(layer "F.Fab")
			(effects
				(font
					(size 1.27 1.27)
				)
			)
		)
		(duplicate_pad_numbers_are_jumpers no)
		(fp_line
			(start 0.7874 -0.4064)
			(end 0.7874 0.4064)
			(stroke
				(width 0.1524)
				(type default)
			)
			(layer "F.SilkS")
		)
		(fp_line
			(start -0.7874 -0.4064)
			(end 0.7874 -0.4064)
			(stroke
				(width 0.1524)
				(type default)
			)
			(layer "F.SilkS")
		)
		(fp_line
			(start 0 0.381)
			(end 0 -0.381)
			(stroke
				(width 0.1524)
				(type default)
			)
			(layer "F.SilkS")
		)
		(fp_line
			(start 0.7874 0.4064)
			(end -0.7874 0.4064)
			(stroke
				(width 0.1524)
				(type default)
			)
			(layer "F.SilkS")
		)
		(fp_line
			(start -0.7874 0.4064)
			(end -0.7874 -0.4064)
			(stroke
				(width 0.1524)
				(type default)
			)
			(layer "F.SilkS")
		)
		(fp_poly
			(pts
				(xy -0.5334 0.254) (xy -0.635 0.254) (xy -0.635 0.2286) (xy -0.635 -0.254) (xy -0.5334 -0.254) (xy -0.5334 -0.2794)
				(xy 0.5334 -0.2794) (xy 0.5334 -0.254) (xy 0.635 -0.254) (xy 0.635 0.254) (xy 0.5334 0.254) (xy 0.5334 0.2794)
				(xy -0.508 0.2794) (xy -0.5334 0.2794)
			)
			(stroke
				(width 0)
				(type default)
			)
			(fill no)
			(layer "F.CrtYd")
		)
		(pad "1" smd rect
			(at 0.40005 0 90)
			(size 0.4572 0.508)
			(layers "F.Cu" "F.Mask" "F.Paste")
			(net "P12V")
		)
		(pad "2" smd rect
			(at -0.40005 0 90)
			(size 0.4572 0.508)
			(layers "F.Cu" "F.Mask" "F.Paste")
			(net "GND")
		)
	)
	(footprint ""
		(layer "F.Cu")
		(at 51.411124 -262.266176 180)
		(property "Reference" "CE7"
			(at -3.278124 3.86588 0)
			(unlocked yes)
			(layer "F.SilkS")
			(effects
				(font
					(size 0.7874 0.5842)
					(thickness 0.1524)
				)
				(justify left)
			)
		)
		(property "Value" ""
			(at 0 0 180)
			(layer "F.Fab")
			(effects
				(font
					(size 1.27 1.27)
				)
			)
		)
		(duplicate_pad_numbers_are_jumpers no)
		(fp_line
			(start 0 -4.2672)
			(end 0 4.2672)
			(stroke
				(width 0.1524)
				(type default)
			)
			(layer "F.SilkS")
		)
		(fp_circle
			(center 0 0)
			(end -4.2672 0)
			(stroke
				(width 0.1524)
				(type default)
			)
			(fill no)
			(layer "F.SilkS")
		)
		(fp_poly
			(pts
				(arc
					(start 0 -4.2672)
					(mid 4.2672 0)
					(end 0 4.2672)
				)
			)
			(stroke
				(width 0)
				(type default)
			)
			(fill yes)
			(layer "F.SilkS")
		)
		(fp_poly
			(pts
				(xy -2.5146 -0.762) (xy -0.9906 -0.762) (xy -0.9906 0.762) (xy -2.5146 0.762)
			)
			(stroke
				(width 0)
				(type default)
			)
			(fill no)
			(layer "B.CrtYd")
		)
		(fp_poly
			(pts
				(arc
					(start 1.7526 0.762)
					(mid 2.291415 -0.538815)
					(end 0.9906 0)
				)
				(arc
					(start 0.9906 0.0254)
					(mid 1.206345 0.546255)
					(end 1.7272 0.762)
				)
			)
			(stroke
				(width 0)
				(type default)
			)
			(fill no)
			(layer "B.CrtYd")
		)
		(fp_poly
			(pts
				(arc
					(start -4.2672 0)
					(mid 4.2672 0)
					(end -4.2672 0)
				)
			)
			(stroke
				(width 0)
				(type default)
			)
			(fill no)
			(layer "F.CrtYd")
		)
		(fp_circle
			(center 0 0)
			(end -4.2672 0)
			(stroke
				(width 0.1)
				(type default)
			)
			(fill no)
			(layer "F.Fab")
		)
		(fp_text user "+"
			(at -5.049266 0.28321 180)
			(unlocked yes)
			(layer "F.SilkS")
			(effects
				(font
					(size 0.7874 0.5842)
					(thickness 0.1524)
				)
				(justify left)
			)
		)
		(fp_text user "+"
			(at -5.6642 -0.34925 180)
			(unlocked yes)
			(layer "F.Fab")
			(effects
				(font
					(size 1.905 1.4224)
					(thickness 0.000001)
				)
				(justify left)
			)
		)
		(pad "1" thru_hole rect
			(at -1.75006 0 180)
			(size 1.397 1.397)
			(drill 0.9144)
			(layers "*.Cu" "*.Mask")
			(remove_unused_layers no)
			(net "P12V")
			(clearance 0.0127)
			(thermal_gap 0.0127)
			(padstack
				(mode front_inner_back)
				(layer "Inner"
					(shape circle)
					(size 1.397 1.397)
					(clearance 0.0127)
				)
				(layer "B.Cu"
					(shape rect)
					(size 1.397 1.397)
					(clearance 0.0127)
				)
			)
		)
		(pad "2" thru_hole circle
			(at 1.75006 0 180)
			(size 1.397 1.397)
			(drill 0.9144)
			(layers "*.Cu" "*.Mask")
			(remove_unused_layers no)
			(net "GND")
			(clearance 0.0127)
			(thermal_gap 0.0127)
		)
	)
	(footprint ""
		(layer "F.Cu")
		(at 26.068274 -184.266078)
		(property "Reference" "R72"
			(at -3.997198 0.128524 0)
			(unlocked yes)
			(layer "F.SilkS")
			(effects
				(font
					(size 0.7874 0.5842)
					(thickness 0.1524)
				)
				(justify left)
			)
		)
		(property "Value" ""
			(at 0 0 0)
			(layer "F.Fab")
			(effects
				(font
					(size 1.27 1.27)
				)
			)
		)
		(duplicate_pad_numbers_are_jumpers no)
		(fp_line
			(start -0.7874 -0.4064)
			(end 0.7874 -0.4064)
			(stroke
				(width 0.1524)
				(type default)
			)
			(layer "F.SilkS")
		)
		(fp_line
			(start -0.7874 0.4064)
			(end -0.7874 -0.4064)
			(stroke
				(width 0.1524)
				(type default)
			)
			(layer "F.SilkS")
		)
		(fp_line
			(start 0.7874 -0.4064)
			(end 0.7874 0.4064)
			(stroke
				(width 0.1524)
				(type default)
			)
			(layer "F.SilkS")
		)
		(fp_line
			(start 0.7874 0.4064)
			(end -0.7874 0.4064)
			(stroke
				(width 0.1524)
				(type default)
			)
			(layer "F.SilkS")
		)
		(fp_poly
			(pts
				(xy -0.508 0.2794) (xy -0.508 0.2286) (xy -0.635 0.2286) (xy -0.635 -0.254) (xy -0.5334 -0.254)
				(xy -0.5334 -0.2794) (xy 0.5334 -0.2794) (xy 0.5334 -0.254) (xy 0.635 -0.254) (xy 0.635 0.254) (xy 0.5334 0.254)
				(xy 0.5334 0.2794)
			)
			(stroke
				(width 0)
				(type default)
			)
			(fill no)
			(layer "F.CrtYd")
		)
		(pad "1" smd rect
			(at 0.40005 0)
			(size 0.4572 0.508)
			(layers "F.Cu" "F.Mask" "F.Paste")
			(net "PSU3_RESET")
		)
		(pad "2" smd rect
			(at -0.40005 0)
			(size 0.4572 0.508)
			(layers "F.Cu" "F.Mask" "F.Paste")
			(net "P12V_STBY")
		)
	)
)
